(kicad_pcb
	(version 20260206)
	(generator "pcbnew")
	(generator_version "10.0")
	(general
		(thickness 1.6)
		(legacy_teardrops no)
	)
	(paper "A4")
	(title_block
		(title "03242023_DA0F0TMBIJ0_F0T_Motherboard_J_brd_V01_OCP.brd")
		(comment 1 "Grand Teton / footprints 716-721 of 6105")
	)
	(layers
		(0 "F.Cu" signal "TOP")
		(4 "In1.Cu" signal "GND")
		(6 "In2.Cu" signal "IN1")
		(8 "In3.Cu" signal "GND1")
		(10 "In4.Cu" signal "IN2")
		(12 "In5.Cu" signal "GND2")
		(14 "In6.Cu" signal "IN3")
		(16 "In7.Cu" signal "GND3")
		(18 "In8.Cu" signal "VCC")
		(20 "In9.Cu" signal "VCC1")
		(22 "In10.Cu" signal "GND4")
		(24 "In11.Cu" signal "IN4")
		(26 "In12.Cu" signal "GND5")
		(28 "In13.Cu" signal "IN5")
		(30 "In14.Cu" signal "GND6")
		(32 "In15.Cu" signal "IN6")
		(34 "In16.Cu" signal "GND7")
		(2 "B.Cu" signal "BOTTOM")
		(9 "F.Adhes" user "F.Adhesive")
		(11 "B.Adhes" user "B.Adhesive")
		(13 "F.Paste" user "Package Geometry/Pastemask Top")
		(15 "B.Paste" user "Package Geometry/Pastemask Bottom")
		(5 "F.SilkS" user "Ref Des/Silkscreen Top")
		(7 "B.SilkS" user "Ref Des/Silkscreen Bottom")
		(1 "F.Mask" user "Board Geometry/Soldermask Top")
		(3 "B.Mask" user "Board Geometry/Soldermask Bottom")
		(17 "Dwgs.User" user "User.Drawings")
		(19 "Cmts.User" user "User.Comments")
		(21 "Eco1.User" user "User.Eco1")
		(23 "Eco2.User" user "User.Eco2")
		(25 "Edge.Cuts" user "Board Geometry/Outline")
		(27 "Margin" user)
		(31 "F.CrtYd" user "Package Geometry/Place Bound Top")
		(29 "B.CrtYd" user "Package Geometry/Place Bound Bottom")
		(35 "F.Fab" user "Ref Des/Assembly Top")
		(33 "B.Fab" user "Ref Des/Assembly Bottom")
	)
	(footprint ""
		(layer "F.Cu")
		(at 448.31254 -41.747948)
		(property "Reference" "C1874"
			(at 0 0 0)
			(layer "F.SilkS")
			(hide yes)
			(effects
				(font
					(size 1.27 1.27)
				)
			)
		)
		(property "Value" ""
			(at 0 0 0)
			(layer "F.Fab")
			(effects
				(font
					(size 1.27 1.27)
				)
			)
		)
		(duplicate_pad_numbers_are_jumpers no)
		(fp_line
			(start -0.7874 -0.4064)
			(end 0.7874 -0.4064)
			(stroke
				(width 0.1524)
				(type default)
			)
			(layer "F.SilkS")
		)
		(fp_line
			(start -0.7874 0.4064)
			(end -0.7874 -0.4064)
			(stroke
				(width 0.1524)
				(type default)
			)
			(layer "F.SilkS")
		)
		(fp_line
			(start 0.7874 -0.4064)
			(end 0.7874 0.4064)
			(stroke
				(width 0.1524)
				(type default)
			)
			(layer "F.SilkS")
		)
		(fp_line
			(start 0.7874 0.4064)
			(end -0.7874 0.4064)
			(stroke
				(width 0.1524)
				(type default)
			)
			(layer "F.SilkS")
		)
		(fp_line
			(start -0.67945 -0.305054)
			(end -0.12065 -0.305054)
			(stroke
				(width 0.1)
				(type default)
			)
			(layer "F.Fab")
		)
		(fp_line
			(start -0.67945 0.3048)
			(end -0.67945 -0.305054)
			(stroke
				(width 0.1)
				(type default)
			)
			(layer "F.Fab")
		)
		(fp_line
			(start -0.12065 -0.305054)
			(end -0.12065 -0.2794)
			(stroke
				(width 0.1)
				(type default)
			)
			(layer "F.Fab")
		)
		(fp_line
			(start -0.12065 -0.2794)
			(end 0.12065 -0.2794)
			(stroke
				(width 0.1)
				(type default)
			)
			(layer "F.Fab")
		)
		(fp_line
			(start -0.12065 0.2794)
			(end -0.12065 0.3048)
			(stroke
				(width 0.1)
				(type default)
			)
			(layer "F.Fab")
		)
		(fp_line
			(start -0.12065 0.3048)
			(end -0.67945 0.3048)
			(stroke
				(width 0.1)
				(type default)
			)
			(layer "F.Fab")
		)
		(fp_line
			(start 0.120396 0.2794)
			(end -0.12065 0.2794)
			(stroke
				(width 0.1)
				(type default)
			)
			(layer "F.Fab")
		)
		(fp_line
			(start 0.120396 0.3048)
			(end 0.120396 0.2794)
			(stroke
				(width 0.1)
				(type default)
			)
			(layer "F.Fab")
		)
		(fp_line
			(start 0.12065 -0.3048)
			(end 0.67945 -0.3048)
			(stroke
				(width 0.1)
				(type default)
			)
			(layer "F.Fab")
		)
		(fp_line
			(start 0.12065 -0.2794)
			(end 0.12065 -0.3048)
			(stroke
				(width 0.1)
				(type default)
			)
			(layer "F.Fab")
		)
		(fp_line
			(start 0.67945 -0.3048)
			(end 0.67945 0.3048)
			(stroke
				(width 0.1)
				(type default)
			)
			(layer "F.Fab")
		)
		(fp_line
			(start 0.67945 0.3048)
			(end 0.120396 0.3048)
			(stroke
				(width 0.1)
				(type default)
			)
			(layer "F.Fab")
		)
		(pad "1" smd circle
			(at -0.40005 0)
			(size 0 0)
			(layers "F.Cu" "F.Mask" "F.Paste")
			(net "P3V3_AUX")
		)
		(pad "2" smd circle
			(at 0.40005 0)
			(size 0 0)
			(layers "F.Cu" "F.Mask" "F.Paste")
			(net "GND")
		)
	)
	(footprint ""
		(layer "F.Cu")
		(at 217.742008 -402.994622 90)
		(property "Reference" "PC3272"
			(at 0 0 90)
			(layer "F.SilkS")
			(hide yes)
			(effects
				(font
					(size 1.27 1.27)
				)
			)
		)
		(property "Value" ""
			(at 0 0 90)
			(layer "F.Fab")
			(effects
				(font
					(size 1.27 1.27)
				)
			)
		)
		(duplicate_pad_numbers_are_jumpers no)
		(fp_line
			(start 0.7874 -0.4064)
			(end 0.7874 0.4064)
			(stroke
				(width 0.1524)
				(type default)
			)
			(layer "F.SilkS")
		)
		(fp_line
			(start -0.7874 -0.4064)
			(end 0.7874 -0.4064)
			(stroke
				(width 0.1524)
				(type default)
			)
			(layer "F.SilkS")
		)
		(fp_line
			(start 0.7874 0.4064)
			(end -0.7874 0.4064)
			(stroke
				(width 0.1524)
				(type default)
			)
			(layer "F.SilkS")
		)
		(fp_line
			(start -0.7874 0.4064)
			(end -0.7874 -0.4064)
			(stroke
				(width 0.1524)
				(type default)
			)
			(layer "F.SilkS")
		)
		(fp_line
			(start -0.12065 -0.305054)
			(end -0.12065 -0.2794)
			(stroke
				(width 0.1)
				(type default)
			)
			(layer "F.Fab")
		)
		(fp_line
			(start -0.67945 -0.305054)
			(end -0.12065 -0.305054)
			(stroke
				(width 0.1)
				(type default)
			)
			(layer "F.Fab")
		)
		(fp_line
			(start 0.67945 -0.3048)
			(end 0.67945 0.3048)
			(stroke
				(width 0.1)
				(type default)
			)
			(layer "F.Fab")
		)
		(fp_line
			(start 0.12065 -0.3048)
			(end 0.67945 -0.3048)
			(stroke
				(width 0.1)
				(type default)
			)
			(layer "F.Fab")
		)
		(fp_line
			(start 0.12065 -0.2794)
			(end 0.12065 -0.3048)
			(stroke
				(width 0.1)
				(type default)
			)
			(layer "F.Fab")
		)
		(fp_line
			(start -0.12065 -0.2794)
			(end 0.12065 -0.2794)
			(stroke
				(width 0.1)
				(type default)
			)
			(layer "F.Fab")
		)
		(fp_line
			(start 0.120396 0.2794)
			(end -0.12065 0.2794)
			(stroke
				(width 0.1)
				(type default)
			)
			(layer "F.Fab")
		)
		(fp_line
			(start -0.12065 0.2794)
			(end -0.12065 0.3048)
			(stroke
				(width 0.1)
				(type default)
			)
			(layer "F.Fab")
		)
		(fp_line
			(start 0.67945 0.3048)
			(end 0.120396 0.3048)
			(stroke
				(width 0.1)
				(type default)
			)
			(layer "F.Fab")
		)
		(fp_line
			(start 0.120396 0.3048)
			(end 0.120396 0.2794)
			(stroke
				(width 0.1)
				(type default)
			)
			(layer "F.Fab")
		)
		(fp_line
			(start -0.12065 0.3048)
			(end -0.67945 0.3048)
			(stroke
				(width 0.1)
				(type default)
			)
			(layer "F.Fab")
		)
		(fp_line
			(start -0.67945 0.3048)
			(end -0.67945 -0.305054)
			(stroke
				(width 0.1)
				(type default)
			)
			(layer "F.Fab")
		)
		(pad "1" smd circle
			(at -0.40005 0 90)
			(size 0 0)
			(layers "F.Cu" "F.Mask" "F.Paste")
			(net "HSC_VDD_R_3")
		)
		(pad "2" smd circle
			(at 0.40005 0 90)
			(size 0 0)
			(layers "F.Cu" "F.Mask" "F.Paste")
			(net "AGND_HSC")
		)
	)
	(footprint ""
		(layer "F.Cu")
		(at 193.60261 -431.424334 180)
		(property "Reference" "C1775"
			(at 0 0 180)
			(layer "F.SilkS")
			(hide yes)
			(effects
				(font
					(size 1.27 1.27)
				)
			)
		)
		(property "Value" ""
			(at 0 0 180)
			(layer "F.Fab")
			(effects
				(font
					(size 1.27 1.27)
				)
			)
		)
		(duplicate_pad_numbers_are_jumpers no)
		(fp_line
			(start 0.7874 0.4064)
			(end -0.7874 0.4064)
			(stroke
				(width 0.1524)
				(type default)
			)
			(layer "F.SilkS")
		)
		(fp_line
			(start 0.7874 -0.4064)
			(end 0.7874 0.4064)
			(stroke
				(width 0.1524)
				(type default)
			)
			(layer "F.SilkS")
		)
		(fp_line
			(start -0.7874 0.4064)
			(end -0.7874 -0.4064)
			(stroke
				(width 0.1524)
				(type default)
			)
			(layer "F.SilkS")
		)
		(fp_line
			(start -0.7874 -0.4064)
			(end 0.7874 -0.4064)
			(stroke
				(width 0.1524)
				(type default)
			)
			(layer "F.SilkS")
		)
		(fp_line
			(start 0.67945 0.3048)
			(end 0.120396 0.3048)
			(stroke
				(width 0.1)
				(type default)
			)
			(layer "F.Fab")
		)
		(fp_line
			(start 0.67945 -0.3048)
			(end 0.67945 0.3048)
			(stroke
				(width 0.1)
				(type default)
			)
			(layer "F.Fab")
		)
		(fp_line
			(start 0.12065 -0.2794)
			(end 0.12065 -0.3048)
			(stroke
				(width 0.1)
				(type default)
			)
			(layer "F.Fab")
		)
		(fp_line
			(start 0.12065 -0.3048)
			(end 0.67945 -0.3048)
			(stroke
				(width 0.1)
				(type default)
			)
			(layer "F.Fab")
		)
		(fp_line
			(start 0.120396 0.3048)
			(end 0.120396 0.2794)
			(stroke
				(width 0.1)
				(type default)
			)
			(layer "F.Fab")
		)
		(fp_line
			(start 0.120396 0.2794)
			(end -0.12065 0.2794)
			(stroke
				(width 0.1)
				(type default)
			)
			(layer "F.Fab")
		)
		(fp_line
			(start -0.12065 0.3048)
			(end -0.67945 0.3048)
			(stroke
				(width 0.1)
				(type default)
			)
			(layer "F.Fab")
		)
		(fp_line
			(start -0.12065 0.2794)
			(end -0.12065 0.3048)
			(stroke
				(width 0.1)
				(type default)
			)
			(layer "F.Fab")
		)
		(fp_line
			(start -0.12065 -0.2794)
			(end 0.12065 -0.2794)
			(stroke
				(width 0.1)
				(type default)
			)
			(layer "F.Fab")
		)
		(fp_line
			(start -0.12065 -0.305054)
			(end -0.12065 -0.2794)
			(stroke
				(width 0.1)
				(type default)
			)
			(layer "F.Fab")
		)
		(fp_line
			(start -0.67945 0.3048)
			(end -0.67945 -0.305054)
			(stroke
				(width 0.1)
				(type default)
			)
			(layer "F.Fab")
		)
		(fp_line
			(start -0.67945 -0.305054)
			(end -0.12065 -0.305054)
			(stroke
				(width 0.1)
				(type default)
			)
			(layer "F.Fab")
		)
		(pad "1" smd circle
			(at -0.40005 0 180)
			(size 0 0)
			(layers "F.Cu" "F.Mask" "F.Paste")
			(net "P3V3_AUX")
		)
		(pad "2" smd circle
			(at 0.40005 0 180)
			(size 0 0)
			(layers "F.Cu" "F.Mask" "F.Paste")
			(net "GND")
		)
	)
	(footprint ""
		(layer "F.Cu")
		(at 225.171762 -69.318378 -90)
		(property "Reference" "R3979"
			(at 0 0 270)
			(layer "F.SilkS")
			(hide yes)
			(effects
				(font
					(size 1.27 1.27)
				)
			)
		)
		(property "Value" ""
			(at 0 0 270)
			(layer "F.Fab")
			(effects
				(font
					(size 1.27 1.27)
				)
			)
		)
		(duplicate_pad_numbers_are_jumpers no)
		(fp_line
			(start -0.7874 0.4064)
			(end -0.7874 -0.4064)
			(stroke
				(width 0.1524)
				(type default)
			)
			(layer "F.SilkS")
		)
		(fp_line
			(start 0.7874 0.4064)
			(end -0.7874 0.4064)
			(stroke
				(width 0.1524)
				(type default)
			)
			(layer "F.SilkS")
		)
		(fp_line
			(start -0.7874 -0.4064)
			(end 0.7874 -0.4064)
			(stroke
				(width 0.1524)
				(type default)
			)
			(layer "F.SilkS")
		)
		(fp_line
			(start 0.7874 -0.4064)
			(end 0.7874 0.4064)
			(stroke
				(width 0.1524)
				(type default)
			)
			(layer "F.SilkS")
		)
		(fp_line
			(start -0.67945 0.3048)
			(end -0.67945 -0.305054)
			(stroke
				(width 0.1)
				(type default)
			)
			(layer "F.Fab")
		)
		(fp_line
			(start -0.12065 0.3048)
			(end -0.67945 0.3048)
			(stroke
				(width 0.1)
				(type default)
			)
			(layer "F.Fab")
		)
		(fp_line
			(start 0.120396 0.3048)
			(end 0.120396 0.2794)
			(stroke
				(width 0.1)
				(type default)
			)
			(layer "F.Fab")
		)
		(fp_line
			(start 0.67945 0.3048)
			(end 0.120396 0.3048)
			(stroke
				(width 0.1)
				(type default)
			)
			(layer "F.Fab")
		)
		(fp_line
			(start -0.12065 0.2794)
			(end -0.12065 0.3048)
			(stroke
				(width 0.1)
				(type default)
			)
			(layer "F.Fab")
		)
		(fp_line
			(start 0.120396 0.2794)
			(end -0.12065 0.2794)
			(stroke
				(width 0.1)
				(type default)
			)
			(layer "F.Fab")
		)
		(fp_line
			(start -0.12065 -0.2794)
			(end 0.12065 -0.2794)
			(stroke
				(width 0.1)
				(type default)
			)
			(layer "F.Fab")
		)
		(fp_line
			(start 0.12065 -0.2794)
			(end 0.12065 -0.3048)
			(stroke
				(width 0.1)
				(type default)
			)
			(layer "F.Fab")
		)
		(fp_line
			(start 0.12065 -0.3048)
			(end 0.67945 -0.3048)
			(stroke
				(width 0.1)
				(type default)
			)
			(layer "F.Fab")
		)
		(fp_line
			(start 0.67945 -0.3048)
			(end 0.67945 0.3048)
			(stroke
				(width 0.1)
				(type default)
			)
			(layer "F.Fab")
		)
		(fp_line
			(start -0.67945 -0.305054)
			(end -0.12065 -0.305054)
			(stroke
				(width 0.1)
				(type default)
			)
			(layer "F.Fab")
		)
		(fp_line
			(start -0.12065 -0.305054)
			(end -0.12065 -0.2794)
			(stroke
				(width 0.1)
				(type default)
			)
			(layer "F.Fab")
		)
		(pad "1" smd circle
			(at -0.40005 0 270)
			(size 0 0)
			(layers "F.Cu" "F.Mask" "F.Paste")
			(net "P3V3_AUX")
		)
		(pad "2" smd circle
			(at 0.40005 0 270)
			(size 0 0)
			(layers "F.Cu" "F.Mask" "F.Paste")
			(net "TP_P3V3_E1S_PWRGD_0")
		)
	)
	(footprint ""
		(layer "F.Cu")
		(at 430.642522 -181.57063 90)
		(property "Reference" "PC1274"
			(at 0 0 90)
			(layer "F.SilkS")
			(hide yes)
			(effects
				(font
					(size 1.27 1.27)
				)
			)
		)
		(property "Value" ""
			(at 0 0 90)
			(layer "F.Fab")
			(effects
				(font
					(size 1.27 1.27)
				)
			)
		)
		(duplicate_pad_numbers_are_jumpers no)
		(fp_line
			(start 0.7874 -0.4064)
			(end 0.7874 0.4064)
			(stroke
				(width 0.1524)
				(type default)
			)
			(layer "F.SilkS")
		)
		(fp_line
			(start -0.7874 -0.4064)
			(end 0.7874 -0.4064)
			(stroke
				(width 0.1524)
				(type default)
			)
			(layer "F.SilkS")
		)
		(fp_line
			(start 0.7874 0.4064)
			(end -0.7874 0.4064)
			(stroke
				(width 0.1524)
				(type default)
			)
			(layer "F.SilkS")
		)
		(fp_line
			(start -0.7874 0.4064)
			(end -0.7874 -0.4064)
			(stroke
				(width 0.1524)
				(type default)
			)
			(layer "F.SilkS")
		)
		(fp_line
			(start -0.12065 -0.305054)
			(end -0.12065 -0.2794)
			(stroke
				(width 0.1)
				(type default)
			)
			(layer "F.Fab")
		)
		(fp_line
			(start -0.67945 -0.305054)
			(end -0.12065 -0.305054)
			(stroke
				(width 0.1)
				(type default)
			)
			(layer "F.Fab")
		)
		(fp_line
			(start 0.67945 -0.3048)
			(end 0.67945 0.3048)
			(stroke
				(width 0.1)
				(type default)
			)
			(layer "F.Fab")
		)
		(fp_line
			(start 0.12065 -0.3048)
			(end 0.67945 -0.3048)
			(stroke
				(width 0.1)
				(type default)
			)
			(layer "F.Fab")
		)
		(fp_line
			(start 0.12065 -0.2794)
			(end 0.12065 -0.3048)
			(stroke
				(width 0.1)
				(type default)
			)
			(layer "F.Fab")
		)
		(fp_line
			(start -0.12065 -0.2794)
			(end 0.12065 -0.2794)
			(stroke
				(width 0.1)
				(type default)
			)
			(layer "F.Fab")
		)
		(fp_line
			(start 0.120396 0.2794)
			(end -0.12065 0.2794)
			(stroke
				(width 0.1)
				(type default)
			)
			(layer "F.Fab")
		)
		(fp_line
			(start -0.12065 0.2794)
			(end -0.12065 0.3048)
			(stroke
				(width 0.1)
				(type default)
			)
			(layer "F.Fab")
		)
		(fp_line
			(start 0.67945 0.3048)
			(end 0.120396 0.3048)
			(stroke
				(width 0.1)
				(type default)
			)
			(layer "F.Fab")
		)
		(fp_line
			(start 0.120396 0.3048)
			(end 0.120396 0.2794)
			(stroke
				(width 0.1)
				(type default)
			)
			(layer "F.Fab")
		)
		(fp_line
			(start -0.12065 0.3048)
			(end -0.67945 0.3048)
			(stroke
				(width 0.1)
				(type default)
			)
			(layer "F.Fab")
		)
		(fp_line
			(start -0.67945 0.3048)
			(end -0.67945 -0.305054)
			(stroke
				(width 0.1)
				(type default)
			)
			(layer "F.Fab")
		)
		(pad "1" smd circle
			(at -0.40005 0 90)
			(size 0 0)
			(layers "F.Cu" "F.Mask" "F.Paste")
			(net "SW_P12V_PVCCINFAON_CPU0_FLT")
		)
		(pad "2" smd circle
			(at 0.40005 0 90)
			(size 0 0)
			(layers "F.Cu" "F.Mask" "F.Paste")
			(net "GND")
		)
	)
	(footprint ""
		(layer "F.Cu")
		(at 299.23359 -367.378996 90)
		(property "Reference" "PR1781"
			(at 0 0 90)
			(layer "F.SilkS")
			(hide yes)
			(effects
				(font
					(size 1.27 1.27)
				)
			)
		)
		(property "Value" ""
			(at 0 0 90)
			(layer "F.Fab")
			(effects
				(font
					(size 1.27 1.27)
				)
			)
		)
		(duplicate_pad_numbers_are_jumpers no)
		(fp_line
			(start 0.7874 -0.4064)
			(end 0.7874 0.4064)
			(stroke
				(width 0.1524)
				(type default)
			)
			(layer "F.SilkS")
		)
		(fp_line
			(start -0.7874 -0.4064)
			(end 0.7874 -0.4064)
			(stroke
				(width 0.1524)
				(type default)
			)
			(layer "F.SilkS")
		)
		(fp_line
			(start 0.7874 0.4064)
			(end -0.7874 0.4064)
			(stroke
				(width 0.1524)
				(type default)
			)
			(layer "F.SilkS")
		)
		(fp_line
			(start -0.7874 0.4064)
			(end -0.7874 -0.4064)
			(stroke
				(width 0.1524)
				(type default)
			)
			(layer "F.SilkS")
		)
		(fp_line
			(start -0.12065 -0.305054)
			(end -0.12065 -0.2794)
			(stroke
				(width 0.1)
				(type default)
			)
			(layer "F.Fab")
		)
		(fp_line
			(start -0.67945 -0.305054)
			(end -0.12065 -0.305054)
			(stroke
				(width 0.1)
				(type default)
			)
			(layer "F.Fab")
		)
		(fp_line
			(start 0.67945 -0.3048)
			(end 0.67945 0.3048)
			(stroke
				(width 0.1)
				(type default)
			)
			(layer "F.Fab")
		)
		(fp_line
			(start 0.12065 -0.3048)
			(end 0.67945 -0.3048)
			(stroke
				(width 0.1)
				(type default)
			)
			(layer "F.Fab")
		)
		(fp_line
			(start 0.12065 -0.2794)
			(end 0.12065 -0.3048)
			(stroke
				(width 0.1)
				(type default)
			)
			(layer "F.Fab")
		)
		(fp_line
			(start -0.12065 -0.2794)
			(end 0.12065 -0.2794)
			(stroke
				(width 0.1)
				(type default)
			)
			(layer "F.Fab")
		)
		(fp_line
			(start 0.120396 0.2794)
			(end -0.12065 0.2794)
			(stroke
				(width 0.1)
				(type default)
			)
			(layer "F.Fab")
		)
		(fp_line
			(start -0.12065 0.2794)
			(end -0.12065 0.3048)
			(stroke
				(width 0.1)
				(type default)
			)
			(layer "F.Fab")
		)
		(fp_line
			(start 0.67945 0.3048)
			(end 0.120396 0.3048)
			(stroke
				(width 0.1)
				(type default)
			)
			(layer "F.Fab")
		)
		(fp_line
			(start 0.120396 0.3048)
			(end 0.120396 0.2794)
			(stroke
				(width 0.1)
				(type default)
			)
			(layer "F.Fab")
		)
		(fp_line
			(start -0.12065 0.3048)
			(end -0.67945 0.3048)
			(stroke
				(width 0.1)
				(type default)
			)
			(layer "F.Fab")
		)
		(fp_line
			(start -0.67945 0.3048)
			(end -0.67945 -0.305054)
			(stroke
				(width 0.1)
				(type default)
			)
			(layer "F.Fab")
		)
		(pad "1" smd circle
			(at -0.40005 0 90)
			(size 0 0)
			(layers "F.Cu" "F.Mask" "F.Paste")
			(net "SW_PVCCFA_EHV_FIVRA_CPU0_BOOT2")
		)
		(pad "2" smd circle
			(at 0.40005 0 90)
			(size 0 0)
			(layers "F.Cu" "F.Mask" "F.Paste")
			(net "SW_PVCCFA_EHV_FIVRA_CPU0_BOOT2_")
		)
	)
)
